(kicad_pcb
	(version 20241229)
	(generator "pcbnew")
	(generator_version "9.0")
	(general
		(thickness 1.599998)
		(legacy_teardrops no)
	)
	(paper "A4")
	(title_block
		(title "Artix - Datacenter Secure Control Module (DC-SCM)")
		(date "2024-11-06")
		(rev "1.1.3")
		(comment 9 "footprints 478-483 of 544")
	)
	(layers
		(0 "F.Cu" signal)
		(4 "In1.Cu" signal)
		(6 "In2.Cu" signal)
		(8 "In3.Cu" signal)
		(10 "In4.Cu" signal)
		(12 "In5.Cu" signal)
		(14 "In6.Cu" signal)
		(2 "B.Cu" signal)
		(9 "F.Adhes" user "F.Adhesive")
		(11 "B.Adhes" user "B.Adhesive")
		(13 "F.Paste" user)
		(15 "B.Paste" user)
		(5 "F.SilkS" user "F.Silkscreen")
		(7 "B.SilkS" user "B.Silkscreen")
		(1 "F.Mask" user)
		(3 "B.Mask" user)
		(17 "Dwgs.User" user "User.Drawings")
		(19 "Cmts.User" user "User.Comments")
		(21 "Eco1.User" user "User.Eco1")
		(23 "Eco2.User" user "User.Eco2")
		(25 "Edge.Cuts" user)
		(27 "Margin" user)
		(31 "F.CrtYd" user "F.Courtyard")
		(29 "B.CrtYd" user "B.Courtyard")
		(35 "F.Fab" user)
		(33 "B.Fab" user)
	)
	(footprint "antmicro-footprints:R_0402_1005Metric"
		(layer "B.Cu")
		(at 101.075 146.375 90)
		(descr "Resistor SMD 0402")
		(tags "resistor SMD 0402")
		(property "Reference" "R167"
			(at 1.274 -8.675 90)
			(layer "B.SilkS")
			(effects
				(font
					(size 0.7 0.7)
					(thickness 0.15)
				)
				(justify right bottom mirror)
			)
		)
		(property "Value" "R_51R_0402"
			(at 0 -1.4 90)
			(layer "B.Fab")
			(effects
				(font
					(size 0.7 0.7)
					(thickness 0.15)
				)
				(justify right bottom mirror)
			)
		)
		(property "Datasheet" "https://www.bourns.com/docs/product-datasheets/cr.pdf"
			(at 0 0 90)
			(layer "F.Fab")
			(hide yes)
			(effects
				(font
					(size 1.27 1.27)
					(thickness 0.15)
				)
			)
		)
		(property "Description" "SMD Chip Resistor, 51 ohm, ± 1%, 63 mW, 0402 [1005 Metric], Thick Film, General Purpose"
			(at 0 0 90)
			(layer "F.Fab")
			(hide yes)
			(effects
				(font
					(size 1.27 1.27)
					(thickness 0.15)
				)
			)
		)
		(property "Author" "Antmicro"
			(at 247.45 45.3 0)
			(layer "B.Fab")
			(hide yes)
			(effects
				(font
					(size 1 1)
					(thickness 0.15)
				)
				(justify mirror)
			)
		)
		(property "License" "Apache-2.0"
			(at 247.45 45.3 0)
			(layer "B.Fab")
			(hide yes)
			(effects
				(font
					(size 1 1)
					(thickness 0.15)
				)
				(justify mirror)
			)
		)
		(property "MPN" "CR0402-FX-51R0GLF"
			(at 247.45 45.3 0)
			(layer "B.Fab")
			(hide yes)
			(effects
				(font
					(size 1 1)
					(thickness 0.15)
				)
				(justify mirror)
			)
		)
		(property "Manufacturer" "Bourns"
			(at 247.45 45.3 0)
			(layer "B.Fab")
			(hide yes)
			(effects
				(font
					(size 1 1)
					(thickness 0.15)
				)
				(justify mirror)
			)
		)
		(property "Tolerance" "1%"
			(at 247.45 45.3 0)
			(layer "B.Fab")
			(hide yes)
			(effects
				(font
					(size 1 1)
					(thickness 0.15)
				)
				(justify mirror)
			)
		)
		(property "Val" "51R"
			(at 247.45 45.3 0)
			(layer "B.Fab")
			(hide yes)
			(effects
				(font
					(size 1 1)
					(thickness 0.15)
				)
				(justify mirror)
			)
		)
		(sheetname "/DDR3/")
		(sheetfile "ddr3.kicad_sch")
		(attr smd exclude_from_pos_files exclude_from_bom dnp)
		(fp_rect
			(start -0.925 0.47)
			(end 0.925 -0.47)
			(stroke
				(width 0.05)
				(type default)
			)
			(fill no)
			(layer "B.CrtYd")
		)
		(fp_rect
			(start -0.5 0.25)
			(end 0.5 -0.25)
			(stroke
				(width 0.15)
				(type solid)
			)
			(fill no)
			(layer "B.Fab")
		)
		(pad "1" smd roundrect
			(at -0.48 0 90)
			(size 0.59 0.64)
			(layers "B.Cu" "B.Mask" "B.Paste")
			(roundrect_rratio 0.25)
			(net 165 "DDR3_A3")
			(pintype "passive")
		)
		(pad "2" smd roundrect
			(at 0.48 0 90)
			(size 0.59 0.64)
			(layers "B.Cu" "B.Mask" "B.Paste")
			(roundrect_rratio 0.25)
			(net 143 "/DDR3/DDR3_VTT")
			(pintype "passive")
		)
	)
	(footprint "antmicro-footprints:R_0402_1005Metric"
		(layer "B.Cu")
		(at 101.175 149.675 -90)
		(descr "Resistor SMD 0402")
		(tags "resistor SMD 0402")
		(property "Reference" "R168"
			(at 2.525 -0.425 90)
			(layer "B.SilkS")
			(effects
				(font
					(size 0.7 0.7)
					(thickness 0.15)
				)
				(justify left bottom mirror)
			)
		)
		(property "Value" "R_51R_0402"
			(at 0 -1.4 90)
			(layer "B.Fab")
			(effects
				(font
					(size 0.7 0.7)
					(thickness 0.15)
				)
				(justify left bottom mirror)
			)
		)
		(property "Datasheet" "https://www.bourns.com/docs/product-datasheets/cr.pdf"
			(at 0 0 270)
			(layer "F.Fab")
			(hide yes)
			(effects
				(font
					(size 1.27 1.27)
					(thickness 0.15)
				)
			)
		)
		(property "Description" "SMD Chip Resistor, 51 ohm, ± 1%, 63 mW, 0402 [1005 Metric], Thick Film, General Purpose"
			(at 0 0 270)
			(layer "F.Fab")
			(hide yes)
			(effects
				(font
					(size 1.27 1.27)
					(thickness 0.15)
				)
			)
		)
		(property "Author" "Antmicro"
			(at -48.5 250.85 0)
			(layer "B.Fab")
			(hide yes)
			(effects
				(font
					(size 1 1)
					(thickness 0.15)
				)
				(justify mirror)
			)
		)
		(property "License" "Apache-2.0"
			(at -48.5 250.85 0)
			(layer "B.Fab")
			(hide yes)
			(effects
				(font
					(size 1 1)
					(thickness 0.15)
				)
				(justify mirror)
			)
		)
		(property "MPN" "CR0402-FX-51R0GLF"
			(at -48.5 250.85 0)
			(layer "B.Fab")
			(hide yes)
			(effects
				(font
					(size 1 1)
					(thickness 0.15)
				)
				(justify mirror)
			)
		)
		(property "Manufacturer" "Bourns"
			(at -48.5 250.85 0)
			(layer "B.Fab")
			(hide yes)
			(effects
				(font
					(size 1 1)
					(thickness 0.15)
				)
				(justify mirror)
			)
		)
		(property "Tolerance" "1%"
			(at -48.5 250.85 0)
			(layer "B.Fab")
			(hide yes)
			(effects
				(font
					(size 1 1)
					(thickness 0.15)
				)
				(justify mirror)
			)
		)
		(property "Val" "51R"
			(at -48.5 250.85 0)
			(layer "B.Fab")
			(hide yes)
			(effects
				(font
					(size 1 1)
					(thickness 0.15)
				)
				(justify mirror)
			)
		)
		(sheetname "/DDR3/")
		(sheetfile "ddr3.kicad_sch")
		(attr smd exclude_from_pos_files exclude_from_bom dnp)
		(fp_rect
			(start -0.925 0.47)
			(end 0.925 -0.47)
			(stroke
				(width 0.05)
				(type default)
			)
			(fill no)
			(layer "B.CrtYd")
		)
		(fp_rect
			(start -0.5 0.25)
			(end 0.5 -0.25)
			(stroke
				(width 0.15)
				(type solid)
			)
			(fill no)
			(layer "B.Fab")
		)
		(pad "1" smd roundrect
			(at -0.48 0 270)
			(size 0.59 0.64)
			(layers "B.Cu" "B.Mask" "B.Paste")
			(roundrect_rratio 0.25)
			(net 158 "DDR3_A0")
			(pintype "passive")
		)
		(pad "2" smd roundrect
			(at 0.48 0 270)
			(size 0.59 0.64)
			(layers "B.Cu" "B.Mask" "B.Paste")
			(roundrect_rratio 0.25)
			(net 143 "/DDR3/DDR3_VTT")
			(pintype "passive")
		)
	)
	(footprint "antmicro-footprints:R_0402_1005Metric"
		(layer "B.Cu")
		(at 102.175 149.675 -90)
		(descr "Resistor SMD 0402")
		(tags "resistor SMD 0402")
		(property "Reference" "R169"
			(at 2.525 -0.425 90)
			(layer "B.SilkS")
			(effects
				(font
					(size 0.7 0.7)
					(thickness 0.15)
				)
				(justify left bottom mirror)
			)
		)
		(property "Value" "R_51R_0402"
			(at 0 -1.4 90)
			(layer "B.Fab")
			(effects
				(font
					(size 0.7 0.7)
					(thickness 0.15)
				)
				(justify left bottom mirror)
			)
		)
		(property "Datasheet" "https://www.bourns.com/docs/product-datasheets/cr.pdf"
			(at 0 0 270)
			(layer "F.Fab")
			(hide yes)
			(effects
				(font
					(size 1.27 1.27)
					(thickness 0.15)
				)
			)
		)
		(property "Description" "SMD Chip Resistor, 51 ohm, ± 1%, 63 mW, 0402 [1005 Metric], Thick Film, General Purpose"
			(at 0 0 270)
			(layer "F.Fab")
			(hide yes)
			(effects
				(font
					(size 1.27 1.27)
					(thickness 0.15)
				)
			)
		)
		(property "Author" "Antmicro"
			(at -47.5 251.85 0)
			(layer "B.Fab")
			(hide yes)
			(effects
				(font
					(size 1 1)
					(thickness 0.15)
				)
				(justify mirror)
			)
		)
		(property "License" "Apache-2.0"
			(at -47.5 251.85 0)
			(layer "B.Fab")
			(hide yes)
			(effects
				(font
					(size 1 1)
					(thickness 0.15)
				)
				(justify mirror)
			)
		)
		(property "MPN" "CR0402-FX-51R0GLF"
			(at -47.5 251.85 0)
			(layer "B.Fab")
			(hide yes)
			(effects
				(font
					(size 1 1)
					(thickness 0.15)
				)
				(justify mirror)
			)
		)
		(property "Manufacturer" "Bourns"
			(at -47.5 251.85 0)
			(layer "B.Fab")
			(hide yes)
			(effects
				(font
					(size 1 1)
					(thickness 0.15)
				)
				(justify mirror)
			)
		)
		(property "Tolerance" "1%"
			(at -47.5 251.85 0)
			(layer "B.Fab")
			(hide yes)
			(effects
				(font
					(size 1 1)
					(thickness 0.15)
				)
				(justify mirror)
			)
		)
		(property "Val" "51R"
			(at -47.5 251.85 0)
			(layer "B.Fab")
			(hide yes)
			(effects
				(font
					(size 1 1)
					(thickness 0.15)
				)
				(justify mirror)
			)
		)
		(sheetname "/DDR3/")
		(sheetfile "ddr3.kicad_sch")
		(attr smd exclude_from_pos_files exclude_from_bom dnp)
		(fp_rect
			(start -0.925 0.47)
			(end 0.925 -0.47)
			(stroke
				(width 0.05)
				(type default)
			)
			(fill no)
			(layer "B.CrtYd")
		)
		(fp_rect
			(start -0.5 0.25)
			(end 0.5 -0.25)
			(stroke
				(width 0.15)
				(type solid)
			)
			(fill no)
			(layer "B.Fab")
		)
		(pad "1" smd roundrect
			(at -0.48 0 270)
			(size 0.59 0.64)
			(layers "B.Cu" "B.Mask" "B.Paste")
			(roundrect_rratio 0.25)
			(net 147 "DDR3_A2")
			(pintype "passive")
		)
		(pad "2" smd roundrect
			(at 0.48 0 270)
			(size 0.59 0.64)
			(layers "B.Cu" "B.Mask" "B.Paste")
			(roundrect_rratio 0.25)
			(net 143 "/DDR3/DDR3_VTT")
			(pintype "passive")
		)
	)
	(footprint "antmicro-footprints:R_0402_1005Metric"
		(layer "B.Cu")
		(at 103.175 149.675 -90)
		(descr "Resistor SMD 0402")
		(tags "resistor SMD 0402")
		(property "Reference" "R170"
			(at 2.525 -0.425 90)
			(layer "B.SilkS")
			(effects
				(font
					(size 0.7 0.7)
					(thickness 0.15)
				)
				(justify left bottom mirror)
			)
		)
		(property "Value" "R_51R_0402"
			(at 0 -1.4 90)
			(layer "B.Fab")
			(effects
				(font
					(size 0.7 0.7)
					(thickness 0.15)
				)
				(justify left bottom mirror)
			)
		)
		(property "Datasheet" "https://www.bourns.com/docs/product-datasheets/cr.pdf"
			(at 0 0 270)
			(layer "F.Fab")
			(hide yes)
			(effects
				(font
					(size 1.27 1.27)
					(thickness 0.15)
				)
			)
		)
		(property "Description" "SMD Chip Resistor, 51 ohm, ± 1%, 63 mW, 0402 [1005 Metric], Thick Film, General Purpose"
			(at 0 0 270)
			(layer "F.Fab")
			(hide yes)
			(effects
				(font
					(size 1.27 1.27)
					(thickness 0.15)
				)
			)
		)
		(property "Author" "Antmicro"
			(at -46.5 252.85 0)
			(layer "B.Fab")
			(hide yes)
			(effects
				(font
					(size 1 1)
					(thickness 0.15)
				)
				(justify mirror)
			)
		)
		(property "License" "Apache-2.0"
			(at -46.5 252.85 0)
			(layer "B.Fab")
			(hide yes)
			(effects
				(font
					(size 1 1)
					(thickness 0.15)
				)
				(justify mirror)
			)
		)
		(property "MPN" "CR0402-FX-51R0GLF"
			(at -46.5 252.85 0)
			(layer "B.Fab")
			(hide yes)
			(effects
				(font
					(size 1 1)
					(thickness 0.15)
				)
				(justify mirror)
			)
		)
		(property "Manufacturer" "Bourns"
			(at -46.5 252.85 0)
			(layer "B.Fab")
			(hide yes)
			(effects
				(font
					(size 1 1)
					(thickness 0.15)
				)
				(justify mirror)
			)
		)
		(property "Tolerance" "1%"
			(at -46.5 252.85 0)
			(layer "B.Fab")
			(hide yes)
			(effects
				(font
					(size 1 1)
					(thickness 0.15)
				)
				(justify mirror)
			)
		)
		(property "Val" "51R"
			(at -46.5 252.85 0)
			(layer "B.Fab")
			(hide yes)
			(effects
				(font
					(size 1 1)
					(thickness 0.15)
				)
				(justify mirror)
			)
		)
		(sheetname "/DDR3/")
		(sheetfile "ddr3.kicad_sch")
		(attr smd exclude_from_pos_files exclude_from_bom dnp)
		(fp_rect
			(start -0.925 0.47)
			(end 0.925 -0.47)
			(stroke
				(width 0.05)
				(type default)
			)
			(fill no)
			(layer "B.CrtYd")
		)
		(fp_rect
			(start -0.5 0.25)
			(end 0.5 -0.25)
			(stroke
				(width 0.15)
				(type solid)
			)
			(fill no)
			(layer "B.Fab")
		)
		(pad "1" smd roundrect
			(at -0.48 0 270)
			(size 0.59 0.64)
			(layers "B.Cu" "B.Mask" "B.Paste")
			(roundrect_rratio 0.25)
			(net 148 "DDR3_A7")
			(pintype "passive")
		)
		(pad "2" smd roundrect
			(at 0.48 0 270)
			(size 0.59 0.64)
			(layers "B.Cu" "B.Mask" "B.Paste")
			(roundrect_rratio 0.25)
			(net 143 "/DDR3/DDR3_VTT")
			(pintype "passive")
		)
	)
	(footprint "antmicro-footprints:R_0402_1005Metric"
		(layer "B.Cu")
		(at 104.175 149.675 -90)
		(descr "Resistor SMD 0402")
		(tags "resistor SMD 0402")
		(property "Reference" "R171"
			(at 2.525 -0.425 90)
			(layer "B.SilkS")
			(effects
				(font
					(size 0.7 0.7)
					(thickness 0.15)
				)
				(justify left bottom mirror)
			)
		)
		(property "Value" "R_51R_0402"
			(at 0 -1.4 90)
			(layer "B.Fab")
			(effects
				(font
					(size 0.7 0.7)
					(thickness 0.15)
				)
				(justify left bottom mirror)
			)
		)
		(property "Datasheet" "https://www.bourns.com/docs/product-datasheets/cr.pdf"
			(at 0 0 270)
			(layer "F.Fab")
			(hide yes)
			(effects
				(font
					(size 1.27 1.27)
					(thickness 0.15)
				)
			)
		)
		(property "Description" "SMD Chip Resistor, 51 ohm, ± 1%, 63 mW, 0402 [1005 Metric], Thick Film, General Purpose"
			(at 0 0 270)
			(layer "F.Fab")
			(hide yes)
			(effects
				(font
					(size 1.27 1.27)
					(thickness 0.15)
				)
			)
		)
		(property "Author" "Antmicro"
			(at -45.5 253.85 0)
			(layer "B.Fab")
			(hide yes)
			(effects
				(font
					(size 1 1)
					(thickness 0.15)
				)
				(justify mirror)
			)
		)
		(property "License" "Apache-2.0"
			(at -45.5 253.85 0)
			(layer "B.Fab")
			(hide yes)
			(effects
				(font
					(size 1 1)
					(thickness 0.15)
				)
				(justify mirror)
			)
		)
		(property "MPN" "CR0402-FX-51R0GLF"
			(at -45.5 253.85 0)
			(layer "B.Fab")
			(hide yes)
			(effects
				(font
					(size 1 1)
					(thickness 0.15)
				)
				(justify mirror)
			)
		)
		(property "Manufacturer" "Bourns"
			(at -45.5 253.85 0)
			(layer "B.Fab")
			(hide yes)
			(effects
				(font
					(size 1 1)
					(thickness 0.15)
				)
				(justify mirror)
			)
		)
		(property "Tolerance" "1%"
			(at -45.5 253.85 0)
			(layer "B.Fab")
			(hide yes)
			(effects
				(font
					(size 1 1)
					(thickness 0.15)
				)
				(justify mirror)
			)
		)
		(property "Val" "51R"
			(at -45.5 253.85 0)
			(layer "B.Fab")
			(hide yes)
			(effects
				(font
					(size 1 1)
					(thickness 0.15)
				)
				(justify mirror)
			)
		)
		(sheetname "/DDR3/")
		(sheetfile "ddr3.kicad_sch")
		(attr smd exclude_from_pos_files exclude_from_bom dnp)
		(fp_rect
			(start -0.925 0.47)
			(end 0.925 -0.47)
			(stroke
				(width 0.05)
				(type default)
			)
			(fill no)
			(layer "B.CrtYd")
		)
		(fp_rect
			(start -0.5 0.25)
			(end 0.5 -0.25)
			(stroke
				(width 0.15)
				(type solid)
			)
			(fill no)
			(layer "B.Fab")
		)
		(pad "1" smd roundrect
			(at -0.48 0 270)
			(size 0.59 0.64)
			(layers "B.Cu" "B.Mask" "B.Paste")
			(roundrect_rratio 0.25)
			(net 149 "DDR3_A9")
			(pintype "passive")
		)
		(pad "2" smd roundrect
			(at 0.48 0 270)
			(size 0.59 0.64)
			(layers "B.Cu" "B.Mask" "B.Paste")
			(roundrect_rratio 0.25)
			(net 143 "/DDR3/DDR3_VTT")
			(pintype "passive")
		)
	)
	(footprint "antmicro-footprints:R_0402_1005Metric"
		(layer "B.Cu")
		(at 104.575 145.175 90)
		(descr "Resistor SMD 0402")
		(tags "resistor SMD 0402")
		(property "Reference" "R172"
			(at 1.375 -8.675 90)
			(layer "B.SilkS")
			(effects
				(font
					(size 0.7 0.7)
					(thickness 0.15)
				)
				(justify right bottom mirror)
			)
		)
		(property "Value" "R_51R_0402"
			(at 0 -1.4 90)
			(layer "B.Fab")
			(effects
				(font
					(size 0.7 0.7)
					(thickness 0.15)
				)
				(justify right bottom mirror)
			)
		)
		(property "Datasheet" "https://www.bourns.com/docs/product-datasheets/cr.pdf"
			(at 0 0 90)
			(layer "F.Fab")
			(hide yes)
			(effects
				(font
					(size 1.27 1.27)
					(thickness 0.15)
				)
			)
		)
		(property "Description" "SMD Chip Resistor, 51 ohm, ± 1%, 63 mW, 0402 [1005 Metric], Thick Film, General Purpose"
			(at 0 0 90)
			(layer "F.Fab")
			(hide yes)
			(effects
				(font
					(size 1.27 1.27)
					(thickness 0.15)
				)
			)
		)
		(property "Author" "Antmicro"
			(at 249.75 40.6 0)
			(layer "B.Fab")
			(hide yes)
			(effects
				(font
					(size 1 1)
					(thickness 0.15)
				)
				(justify mirror)
			)
		)
		(property "License" "Apache-2.0"
			(at 249.75 40.6 0)
			(layer "B.Fab")
			(hide yes)
			(effects
				(font
					(size 1 1)
					(thickness 0.15)
				)
				(justify mirror)
			)
		)
		(property "MPN" "CR0402-FX-51R0GLF"
			(at 249.75 40.6 0)
			(layer "B.Fab")
			(hide yes)
			(effects
				(font
					(size 1 1)
					(thickness 0.15)
				)
				(justify mirror)
			)
		)
		(property "Manufacturer" "Bourns"
			(at 249.75 40.6 0)
			(layer "B.Fab")
			(hide yes)
			(effects
				(font
					(size 1 1)
					(thickness 0.15)
				)
				(justify mirror)
			)
		)
		(property "Tolerance" "1%"
			(at 249.75 40.6 0)
			(layer "B.Fab")
			(hide yes)
			(effects
				(font
					(size 1 1)
					(thickness 0.15)
				)
				(justify mirror)
			)
		)
		(property "Val" "51R"
			(at 249.75 40.6 0)
			(layer "B.Fab")
			(hide yes)
			(effects
				(font
					(size 1 1)
					(thickness 0.15)
				)
				(justify mirror)
			)
		)
		(sheetname "/DDR3/")
		(sheetfile "ddr3.kicad_sch")
		(attr smd exclude_from_pos_files exclude_from_bom dnp)
		(fp_rect
			(start -0.925 0.47)
			(end 0.925 -0.47)
			(stroke
				(width 0.05)
				(type default)
			)
			(fill no)
			(layer "B.CrtYd")
		)
		(fp_rect
			(start -0.5 0.25)
			(end 0.5 -0.25)
			(stroke
				(width 0.15)
				(type solid)
			)
			(fill no)
			(layer "B.Fab")
		)
		(pad "1" smd roundrect
			(at -0.48 0 90)
			(size 0.59 0.64)
			(layers "B.Cu" "B.Mask" "B.Paste")
			(roundrect_rratio 0.25)
			(net 167 "DDR3_A5")
			(pintype "passive")
		)
		(pad "2" smd roundrect
			(at 0.48 0 90)
			(size 0.59 0.64)
			(layers "B.Cu" "B.Mask" "B.Paste")
			(roundrect_rratio 0.25)
			(net 143 "/DDR3/DDR3_VTT")
			(pintype "passive")
		)
	)
)
